#ISCELL
  pure_quanta quanta_title_block_c *
  *
#ISCELL
  standard offpage *
  page317_i1
#ISCELL
  standard offpage *
  page317_i10
#ISCELL
  standard offpage *
  page317_i11
#ISCELL
  standard offpage *
  page317_i12
#ISCELL
  pure_quanta_power universal_gnd *
  page317_i13
#ISCELL
  standard offpage *
  page317_i14
#ISCELL
  standard offpage *
  page317_i15
#ISCELL
  standard offpage *
  page317_i16
#ISCELL
  standard offpage *
  page317_i17
#ISCELL
  standard offpage *
  page317_i18
#ISCELL
  standard offpage *
  page317_i19
#ISCELL
  standard offpage *
  page317_i2
#ISCELL
  standard offpage *
  page317_i20
#ISCELL
  standard offpage *
  page317_i21
#ISCELL
  standard offpage *
  page317_i22
#ISCELL
  standard offpage *
  page317_i23
#ISCELL
  standard offpage *
  page317_i24
#ISCELL
  standard offpage *
  page317_i25
#ISCELL
  standard offpage *
  page317_i26
#ISCELL
  standard offpage *
  page317_i27
#ISCELL
  standard offpage *
  page317_i28
#ISCELL
  standard offpage *
  page317_i29
#ISCELL
  standard offpage *
  page317_i3
#ISCELL
  standard offpage *
  page317_i30
#ISCELL
  standard offpage *
  page317_i31
#ISCELL
  standard offpage *
  page317_i32
#ISCELL
  standard offpage *
  page317_i33
#ISCELL
  standard offpage *
  page317_i34
#ISCELL
  standard offpage *
  page317_i35
#ISCELL
  standard offpage *
  page317_i36
#ISCELL
  standard offpage *
  page317_i37
#ISCELL
  standard offpage *
  page317_i38
#ISCELL
  standard offpage *
  page317_i39
#ISCELL
  standard offpage *
  page317_i4
#ISCELL
  standard offpage *
  page317_i40
#ISCELL
  standard offpage *
  page317_i41
#ISCELL
  standard offpage *
  page317_i42
#ISCELL
  standard offpage *
  page317_i43
#ISCELL
  standard offpage *
  page317_i44
#ISCELL
  standard offpage *
  page317_i45
#ISCELL
  standard offpage *
  page317_i46
#ISCELL
  standard offpage *
  page317_i47
#ISCELL
  pure_quanta_power universal_gnd *
  page317_i48
#CELL
  pure_quanta conn112_10137002101lf *
  page317_i49
#ISCELL
  standard offpage *
  page317_i5
#ISCELL
  standard offpage *
  page317_i50
#ISCELL
  standard offpage *
  page317_i51
#ISCELL
  standard offpage *
  page317_i52
#ISCELL
  standard offpage *
  page317_i53
#ISCELL
  standard offpage *
  page317_i54
#ISCELL
  standard offpage *
  page317_i55
#ISCELL
  standard offpage *
  page317_i56
#ISCELL
  standard offpage *
  page317_i57
#ISCELL
  standard offpage *
  page317_i58
#ISCELL
  standard offpage *
  page317_i59
#ISCELL
  standard offpage *
  page317_i6
#ISCELL
  standard offpage *
  page317_i60
#ISCELL
  standard offpage *
  page317_i61
#ISCELL
  standard offpage *
  page317_i62
#ISCELL
  standard offpage *
  page317_i63
#ISCELL
  standard offpage *
  page317_i64
#ISCELL
  standard offpage *
  page317_i65
#ISCELL
  standard offpage *
  page317_i66
#ISCELL
  standard offpage *
  page317_i67
#ISCELL
  standard offpage *
  page317_i68
#ISCELL
  standard offpage *
  page317_i69
#ISCELL
  standard offpage *
  page317_i7
#CELL
  pure_quanta conn112_10137002101lf *
  page317_i70
#ISCELL
  standard offpage *
  page317_i71
#ISCELL
  standard offpage *
  page317_i8
#ISCELL
  standard offpage *
  page317_i9
